FILE_TYPE = CONNECTIVITY;
{Allegro Design Entry HDL 16.6-p007 (v16-6-112F) 10/10/2012}
"PAGE_NUMBER" = 114;
0"NC";
1"GND\g";
2"GND\g";
3"GND\g";
4"GND\g";
5"GND\g";
6"CLK_100M_PCH_XDP_DP";
7"CLK_100M_PCH_SLOTX24_S5_DN";
8"CLK_100M_AIRMAX8_PE1_DP";
9"CLK_100M_M2_DP";
10"CLK_100M_M2_DN";
11"CLK_100M_SPRV_DP";
12"CLK_100M_SPRV_DN";
13"CLK_100M_MEZZ4_DP";
14"CLK_100M_MEZZ4_DN";
15"CLK_100M_MEZZ3_DP";
16"CLK_100M_MEZZ1_DN";
17"CLK_100M_MEZZ3_DN";
18"CLK_100M_MEZZ2_DP";
19"CLK_100M_MEZZ2_DN";
20"CLK_100M_PCH_SLOTX24_S4_DN";
21"CLK_100M_PCH_SLOTX24_S5_DP";
22"CLK_100M_MEZZ1_DP";
23"H_PMSYNC_CLK_24M";
24"CLK_100M_DB1200_DP";
25"CLK_100M_PCH_SLOTX24_S0_DP";
26"CLK_100M_PCH_SLOTX24_S3_DN";
27"CLK_100M_PCH_SLOTX24_S1_DP";
28"CLK_100M_PCH_SLOTX24_S2_DN";
29"CLK_100M_PCH_SLOTX24_S4_DP";
30"CLK_100M_PCH_SLOTX24_S2_DP";
31"CLK_100M_PCH_SLOTX24_S1_DN";
32"CLK_100M_PCH_SLOTX24_S0_DN";
33"CLK_100M_DB1200_DN";
34"CLK_100M_AIRMAX8_PE1_DN";
35"CLK_100M_PCH_SLOTX24_S3_DP";
36"TP_CLK_24M_PMSYNC2";
37"XTAL_PCH_48M_OUT";
38"XTAL_PCH_48M_IN";
39"H_PMSYNC_CLK_24M_R";
40"CLK_48M_USB_BMC";
41"CLK_100M_BMC_PE_R_DN";
42"CLK_100M_BMC_PE_R_DP";
43"XTAL_33K_RTC2";
44"TP_CLK_100M_PLAT1_DP";
45"TP_CLK_100M_NSSCC0_DP";
46"CLK_100M_BMC_PE_DP";
47"A_PCH_XCLK_BIASREF";
48"XTAL_PCH_48M_IN";
49"XTAL_33K_RTC1";
50"XTAL_33K_RTC2";
51"XTAL_PCH_48M_OUT";
52"TP_PCH_RSVD65";
53"TP_CLK_100M_NSSCC1_DN";
54"TP_CLK_100M_PLAT1_DN";
55"TP_CLK_100M_NSSCC0_DN";
56"CLK_100M_BMC_PE_DN";
57"TP_PCH_RSVD64";
58"TP_CLK_100M_NSSCC1_DP";
59"CLK_100M_PCH_XDP_DN";
60"XTAL_33K_RTC1";
%"RES"
"1","(2300,1350)","0","mstr_discrete","I110";
;
CDS_SEC"1"
PACK_TYPE"0402"
MATERIAL"CHIP"
TOLERANCE"1%"
VALUE"10.0"
LOCATION"R8B20"
WATTAGE"1/16W"
PART_NUMBER"G21796-066"
SEC"1"
SEC_TYPE"0402"
ROOM"SB"
CDS_LOCATION"R8B20"
CDS_LIB"mstr_discrete";
"B"
$PN"2"23;
"A"
$PN"1"39;
%"RES"
"2","(2900,1100)","0","mstr_discrete","I124";
;
CDS_SEC"1"
LOCATION"R8B21"
TOLERANCE"1%"
PACK_TYPE"0402"
PART_NUMBER"G21796-047"
VALUE"49.9"
WATTAGE"1/16W"
MATERIAL"EMPTY"
SEC_TYPE"0402"
SEC"1"
ROOM"SB"
CDS_LOCATION"R8B21"
CDS_LIB"mstr_discrete";
"A"
$PN"1"23;
"B"
$PN"2"1;
%"GND"
"1","(2900,850)","0","mstr_symbols","I125";
;
SIZE"1B"
VOLTAGE"0.0V"
CDS_LIB"mstr_symbols"
BODY_TYPE"PLUMBING"
HDL_POWER"GND";
"A\NAC"1;
%"RES"
"2","(-3150,2750)","0","mstr_discrete","I149";
;
CDS_SEC"1"
MATERIAL"CHIP"
WATTAGE"1/16W"
TOLERANCE"1.0%"
VALUE"169"
PACK_TYPE"0402"
PART_NUMBER"G21796-276"
LOCATION"R3N1"
CDS_LIB"mstr_discrete"
ROOM"SB"
CDS_LOCATION"R3N1"
SEC"1"
SEC_TYPE"0402";
"A"
$PN"1"47;
"B"
$PN"2"2;
%"GND"
"1","(-3150,2500)","0","mstr_symbols","I150";
;
SIZE"1B"
CDS_LIB"mstr_symbols"
VOLTAGE"0.0V"
BODY_TYPE"PLUMBING"
HDL_POWER"GND";
"A\NAC"2;
%"RES"
"1","(-1625,2850)","0","mstr_discrete","I191";
;
CDS_SEC"1"
GROUP"AST2500"
PART_NUMBER"G21497-005"
TOLERANCE"5%"
VALUE"0.0"
PACK_TYPE"0402"
WATTAGE"1/16W"
LOCATION"R7C4"
CDS_LOCATION"R7C4"
ROOM"CPU0"
SEC"1"
SEC_TYPE"0402"
CDS_LIB"mstr_discrete"
BOM_COST"PROC_SIDEBAND"
MATERIAL"CHIP";
"B"
$PN"2"46;
"A"
$PN"1"42;
%"RES"
"1","(-1275,2800)","0","mstr_discrete","I192";
;
CDS_SEC"1"
VALUE"0.0"
GROUP"AST2500"
TOLERANCE"5%"
PACK_TYPE"0402"
LOCATION"R7C2"
WATTAGE"1/16W"
PART_NUMBER"G21497-005"
CDS_LOCATION"R7C2"
ROOM"CPU0"
SEC"1"
SEC_TYPE"0402"
CDS_LIB"mstr_discrete"
BOM_COST"PROC_SIDEBAND"
MATERIAL"CHIP";
"B"
$PN"2"56;
"A"
$PN"1"41;
%"CAP"
"1","(-2850,2750)","0","mstr_discrete","I193";
;
CDS_SEC"1"
CDS_LOCATION"C3W1"
LOCATION"C3W1"
PACK_TYPE"0402"
TOLERANCE"10%"
VOLTAGE"6.3V"
VALUE"1.0UF"
MATERIAL"EMPTY"
PART_NUMBER"D97712-004"
CDS_LIB"mstr_discrete"
SEC_TYPE"0402"
SEC"1";
"A"
$PN"1"47;
"B"
$PN"2"3;
%"GND"
"1","(-2850,2500)","0","mstr_symbols","I194";
;
VOLTAGE"0.0V"
CDS_LIB"mstr_symbols"
SIZE"1B"
BODY_TYPE"PLUMBING"
HDL_POWER"GND";
"A\NAC"3;
%"CAP"
"1","(-275,-225)","0","mstr_discrete","I195";
;
CDS_SEC"1"
VALUE"15.0PF"
VOLTAGE"50V"
LOCATION"C7C13"
PART_NUMBER"A36095-047"
TOLERANCE"5%"
MATERIAL"COG"
PACK_TYPE"0402LF"
SEC_TYPE"0402LF"
SEC"1"
CDS_LIB"mstr_discrete"
ROOM"SB"
BOM_COST"SYS_CLOCK"
CDS_LOCATION"C7C13";
"A"
$PN"1"49;
"B"
$PN"2"5;
%"CAP"
"1","(225,-225)","0","mstr_discrete","I196";
;
CDS_SEC"1"
LOCATION"C7C15"
VALUE"15.0PF"
VOLTAGE"50V"
MATERIAL"COG"
TOLERANCE"5%"
PART_NUMBER"A36095-047"
PACK_TYPE"0402LF"
SEC_TYPE"0402LF"
SEC"1"
CDS_LIB"mstr_discrete"
ROOM"SB"
BOM_COST"SYS_CLOCK"
CDS_LOCATION"C7C15";
"A"
$PN"1"50;
"B"
$PN"2"5;
%"LBG_CORE_QAT_EXT_D"
"1","(525,2150)","0","mstr_u_proc","I40";
;
CDS_SEC"1"
MATERIAL"IC"
LOCATION"U7C1"
PART_NUMBER"H91415-002"
CDS_LIB"mstr_u_proc"
PACK_TYPE"BGA1"
CDS_LOCATION"U7C1"
BOM_COST"SB"
SEC"1"
SEC_TYPE"BGA1"
ROOM"SB";
"CLKOUT_ITPXDPN"
$PN"A39"59;
"CLKOUT_ITPXDPP"
$PN"C39"6;
"CLKOUT_NSSCCAP0N"
$PN"A32"55;
"CLKOUT_NSSCCAP0P"
$PN"C32"45;
"CLKOUT_NSSCCAP1N"
$PN"B38"53;
"CLKOUT_NSSCCAP1P"
$PN"D38"58;
"CLKOUT_PLAT0N"
$PN"B29"56;
"CLKOUT_PLAT0P"
$PN"D29"46;
"CLKOUT_PLAT1N"
$PN"B40"54;
"CLKOUT_PLAT1P"
$PN"D40"44;
"CLKOUT_SRCN<15>"
$PN"K27"10;
"CLKOUT_SRCN<14>"
$PN"C20"12;
"CLKOUT_SRCN<13>"
$PN"C24"0;
"CLKOUT_SRCN<12>"
$PN"K24"0;
"CLKOUT_SRCN<11>"
$PN"B21"14;
"CLKOUT_SRCN<10>"
$PN"B23"17;
"CLKOUT_SRCN<9>"
$PN"J26"19;
"CLKOUT_SRCN<8>"
$PN"D31"16;
"CLKOUT_SRCN<7>"
$PN"H31"7;
"CLKOUT_SRCN<6>"
$PN"D33"20;
"CLKOUT_SRCN<5>"
$PN"J40"26;
"CLKOUT_SRCN<4>"
$PN"A28"28;
"CLKOUT_SRCN<3>"
$PN"K42"31;
"CLKOUT_SRCN<2>"
$PN"J33"32;
"CLKOUT_SRCN<1>"
$PN"K35"33;
"CLKOUT_SRCN<0>"
$PN"K38"34;
"CLKOUT_SRCP<15>"
$PN"H27"9;
"CLKOUT_SRCP<14>"
$PN"A20"11;
"CLKOUT_SRCP<13>"
$PN"A24"0;
"CLKOUT_SRCP<12>"
$PN"H24"0;
"CLKOUT_SRCP<11>"
$PN"D21"13;
"CLKOUT_SRCP<10>"
$PN"D23"15;
"CLKOUT_SRCP<9>"
$PN"G26"18;
"CLKOUT_SRCP<8>"
$PN"B31"22;
"CLKOUT_SRCP<7>"
$PN"K31"21;
"CLKOUT_SRCP<6>"
$PN"B33"29;
"CLKOUT_SRCP<5>"
$PN"G40"35;
"CLKOUT_SRCP<4>"
$PN"C28"30;
"CLKOUT_SRCP<3>"
$PN"H42"27;
"CLKOUT_SRCP<2>"
$PN"G33"25;
"CLKOUT_SRCP<1>"
$PN"H35"24;
"CLKOUT_SRCP<0>"
$PN"H38"8;
"CLOCKSE_BMCCLK"
$PN"BW50"40;
"CLOCKSE_PMSYNCCLK1"
$PN"BY51"39;
"CLOCKSE_PMSYNCCLK2"
$PN"BV51"36;
"RSVD<65>"
$PN"A26"52;
"RSVD<64>"
$PN"C26"57;
"RTCX1"
$PN"K17"60;
"RTCX2"
$PN"H17"43;
"XCLK_BIASREF"
$PN"G44"47;
"XTAL_IN"
$PN"B35"38;
"XTAL_OUT"
$PN"D35"37;
%"CAP"
"1","(-1525,-200)","0","mstr_discrete","I47";
;
CDS_SEC"1"
MATERIAL"COG"
TOLERANCE"5%"
LOCATION"C7C5"
PACK_TYPE"0402LF"
CONFIG"78.6R864.1FL"
PART_NUMBER"A36095-047"
VOLTAGE"50V"
NEW_VALUE"6.8PF"
CDS_LOCATION"C7C5"
BOM_COST"SYS_CLOCK"
CDS_LIB"mstr_discrete"
ROOM"SB"
SEC"1"
SEC_TYPE"0402LF"
VALUE"15.0PF";
"A"
$PN"1"51;
"B"
$PN"2"4;
%"RES"
"1","(-1775,475)","0","mstr_discrete","I48";
;
CDS_SEC"1"
PART_NUMBER"G22369-010"
PACK_TYPE"0603"
LOCATION"R7C1"
VALUE"200K"
WATTAGE"1/10W"
TOLERANCE"0.1%"
MATERIAL"CHIP"
SEC_TYPE"0603"
SEC"1"
CDS_LOCATION"R7C1"
CDS_LIB"mstr_discrete"
ROOM"SB";
"B"
$PN"2"51;
"A"
$PN"1"48;
%"CRYSTAL"
"1","(-1775,150)","0","mstr_discrete","I49";
;
CDS_SEC"1"
LOCATION"Y7C1"
VALUE"48.000MHZ"
MATERIAL"IC"
PART_NUMBER"D71700-058"
CDS_LIB"mstr_discrete"
PACK_TYPE"2013"
CDS_LOCATION"Y7C1"
SEC_TYPE"2013"
SEC"1"
ROOM"SB";
"B"
$PN"3"51;
"A"
$PN"1"48;
%"CAP"
"1","(-2025,-200)","0","mstr_discrete","I50";
;
CDS_SEC"1"
MATERIAL"COG"
TOLERANCE"5%"
LOCATION"C7C4"
PART_NUMBER"A36095-047"
PACK_TYPE"0402LF"
CONFIG"78.6R864.1FL"
VOLTAGE"50V"
NEW_VALUE"6.8PF"
SEC_TYPE"0402LF"
SEC"1"
CDS_LIB"mstr_discrete"
CDS_LOCATION"C7C4"
ROOM"SB"
BOM_COST"SYS_CLOCK"
VALUE"15.0PF";
"A"
$PN"1"48;
"B"
$PN"2"4;
%"GND"
"1","(-2025,-600)","0","mstr_symbols","I53";
;
BOM_COST"SYS_CLOCK"
VOLTAGE"0"
SIZE"1B"
CDS_LIB"mstr_symbols"
BODY_TYPE"PLUMBING"
HDL_POWER"GND";
"A\NAC"4;
%"RES"
"1","(-25,475)","0","mstr_discrete","I54";
;
LOCATION"R7C6"
PART_NUMBER"G22026-112"
TOLERANCE"1.0%"
WATTAGE"1/10W"
VALUE"10M"
MATERIAL"CHIP"
PACK_TYPE"0603"
CDS_SEC"1"
$SEC"1"
CDS_LOCATION"R7C6"
CDS_LIB"mstr_discrete"
ROOM"SB"
BOM_COST"SYS_CLOCK";
"B"
$PN"2"50;
"A"
$PN"1"49;
%"CRYSTAL"
"1","(-25,125)","0","mstr_discrete","I55";
;
CDS_SEC"1"
PART_NUMBER"C13544-023"
LOCATION"Y7C2"
VALUE"32.768KHZ"
MATERIAL"IC"
SEC_TYPE"SM"
SEC"1"
ROOM"SB"
CDS_LOCATION"Y7C2"
CDS_LIB"mstr_discrete"
PACK_TYPE"SM";
"B"
$PN"2"50;
"A"
$PN"1"49;
%"GND"
"1","(-275,-575)","0","mstr_symbols","I57";
;
VOLTAGE"0"
SIZE"1B"
CDS_LIB"mstr_symbols"
BOM_COST"SYS_CLOCK"
BODY_TYPE"PLUMBING"
HDL_POWER"GND";
"A\NAC"5;
END.
